# TIMECARD (Time Appliance Project (Time Card)) — schematic netlist excerpt (pin names and nets, part order shuffled) for the footprints in the layout excerpt that follows; sources: Cadence DE-HDL packaged netlist, KiCad conversion of R4006-B0001-02_R01.brd

R152  RESISTOR  4.7KOHM 1%  pkg SMC_0402R_H016  page 16 : \1\ = SG ; \2\ = UNNAMED_5_PCA9546APWTSSOP16_I33
C146  CAPACITOR  0.1UF 10V 10%  pkg SMC_0402R_H022  page 14 : \1\ = XP2R5V_FPGA ; \2\ = SG

(kicad_pcb
	(version 20260206)
	(generator "pcbnew")
	(generator_version "10.0")
	(general
		(thickness 1.6)
		(legacy_teardrops no)
	)
	(paper "A4")
	(title_block
		(title "timecard-production-celestica-r4006 — R4006-B0001-02_R01.brd")
		(comment 1 "Time Appliance Project (Time Card) / footprints 1011-1012 of 1113")
	)
	(layers
		(0 "F.Cu" signal "TOP")
		(4 "In1.Cu" signal "L02_GND1")
		(6 "In2.Cu" signal "L03_SIG1")
		(8 "In3.Cu" signal "L04_GND2")
		(10 "In4.Cu" signal "L05_VCC1")
		(12 "In5.Cu" signal "L06_VCC2")
		(14 "In6.Cu" signal "L07_GND3")
		(16 "In7.Cu" signal "L08_SIG2")
		(18 "In8.Cu" signal "L09_GND4")
		(2 "B.Cu" signal "BOTTOM")
		(9 "F.Adhes" user "F.Adhesive")
		(11 "B.Adhes" user "B.Adhesive")
		(13 "F.Paste" user "Package Geometry/Pastemask Top")
		(15 "B.Paste" user "Package Geometry/Pastemask Bottom")
		(5 "F.SilkS" user "Ref Des/Silkscreen Top")
		(7 "B.SilkS" user "Ref Des/Silkscreen Bottom")
		(1 "F.Mask" user "Board Geometry/Soldermask Top")
		(3 "B.Mask" user "Board Geometry/Soldermask Bottom")
		(17 "Dwgs.User" user "User.Drawings")
		(19 "Cmts.User" user "User.Comments")
		(21 "Eco1.User" user "User.Eco1")
		(23 "Eco2.User" user "User.Eco2")
		(25 "Edge.Cuts" user "Board Geometry/Outline")
		(27 "Margin" user)
		(31 "F.CrtYd" user "Package Geometry/Place Bound Top")
		(29 "B.CrtYd" user "Package Geometry/Place Bound Bottom")
		(35 "F.Fab" user "Ref Des/Assembly Top")
		(33 "B.Fab" user "Ref Des/Assembly Bottom")
	)
	(footprint ""
		(layer "B.Cu")
		(at 105.347008 -37.82314)
		(property "Reference" "C146"
			(at -41.656508 1.37795 0)
			(unlocked yes)
			(layer "B.SilkS")
			(effects
				(font
					(size 0.635 0.4064)
					(thickness 0.1524)
				)
				(justify mirror)
			)
		)
		(property "Value" "VAL*"
			(at 0 3.718306 0)
			(unlocked yes)
			(layer "B.Fab")
			(hide yes)
			(effects
				(font
					(size 0.7874 0.5842)
					(thickness 0.127)
				)
				(justify mirror)
			)
		)
		(property "Tolerance" "TOL*"
			(at 0 4.861306 0)
			(unlocked yes)
			(layer "Cmts.User")
			(hide yes)
			(effects
				(font
					(size 0.7874 0.5842)
					(thickness 0.127)
				)
				(justify mirror)
			)
		)
		(property "User Part Number" "PARTNUM*"
			(at 0 2.575306 0)
			(unlocked yes)
			(layer "Cmts.User")
			(hide yes)
			(effects
				(font
					(size 0.7874 0.5842)
					(thickness 0.127)
				)
				(justify mirror)
			)
		)
		(property "Device Type" "CAPACITOR-G105-0B104-CK,0.1UF,A"
			(at 0 1.432306 0)
			(unlocked yes)
			(layer "B.Fab")
			(hide yes)
			(effects
				(font
					(size 0.7874 0.5842)
					(thickness 0.127)
				)
				(justify mirror)
			)
		)
		(duplicate_pad_numbers_are_jumpers no)
		(fp_line
			(start -0.970026 -0.4699)
			(end -0.970026 0.4699)
			(stroke
				(width 0.1)
				(type default)
			)
			(layer "B.SilkS")
		)
		(fp_line
			(start -0.970026 0.4699)
			(end 0.970026 0.4699)
			(stroke
				(width 0.1)
				(type default)
			)
			(layer "B.SilkS")
		)
		(fp_line
			(start 0.970026 -0.4699)
			(end -0.970026 -0.4699)
			(stroke
				(width 0.1)
				(type default)
			)
			(layer "B.SilkS")
		)
		(fp_line
			(start 0.970026 0.4699)
			(end 0.970026 -0.4699)
			(stroke
				(width 0.1)
				(type default)
			)
			(layer "B.SilkS")
		)
		(fp_poly
			(pts
				(xy 0.970026 0.4699) (xy -0.970026 0.4699) (xy -0.970026 -0.4699) (xy 0.970026 -0.4699)
			)
			(stroke
				(width 0)
				(type default)
			)
			(fill no)
			(layer "B.CrtYd")
		)
		(fp_line
			(start -0.508 -0.3048)
			(end -0.508 0.3048)
			(stroke
				(width 0.1)
				(type default)
			)
			(layer "B.Fab")
		)
		(fp_line
			(start -0.508 0.3048)
			(end 0.508 0.3048)
			(stroke
				(width 0.1)
				(type default)
			)
			(layer "B.Fab")
		)
		(fp_line
			(start 0.508 -0.3048)
			(end -0.508 -0.3048)
			(stroke
				(width 0.1)
				(type default)
			)
			(layer "B.Fab")
		)
		(fp_line
			(start 0.508 0.3048)
			(end 0.508 -0.3048)
			(stroke
				(width 0.1)
				(type default)
			)
			(layer "B.Fab")
		)
		(pad "1" smd circle
			(at 0.500126 0 180)
			(size 0.635 0.635)
			(layers "B.Cu" "B.Mask" "B.Paste")
			(net "XP2R5V_FPGA")
		)
		(pad "2" smd circle
			(at -0.500126 0 180)
			(size 0.635 0.635)
			(layers "B.Cu" "B.Mask" "B.Paste")
			(net "SG")
		)
	)
	(footprint ""
		(layer "B.Cu")
		(at 83.2358 -82.55 180)
		(property "Reference" "R152"
			(at 0.1778 -2.32537 0)
			(unlocked yes)
			(layer "B.SilkS")
			(effects
				(font
					(size 0.7874 0.5842)
					(thickness 0.1524)
				)
				(justify mirror)
			)
		)
		(property "Value" "VAL*"
			(at -0.02032 2.13233 180)
			(unlocked yes)
			(layer "B.Fab")
			(hide yes)
			(effects
				(font
					(size 0.7874 0.5842)
					(thickness 0.1524)
				)
				(justify mirror)
			)
		)
		(property "Tolerance" "TOL*"
			(at -0.044704 3.05435 180)
			(unlocked yes)
			(layer "Cmts.User")
			(hide yes)
			(effects
				(font
					(size 0.7874 0.5842)
					(thickness 0.1524)
				)
				(justify mirror)
			)
		)
		(property "User Part Number" "PARTNUM*"
			(at -0.02032 4.024884 180)
			(unlocked yes)
			(layer "Cmts.User")
			(hide yes)
			(effects
				(font
					(size 0.7874 0.5842)
					(thickness 0.1524)
				)
				(justify mirror)
			)
		)
		(property "Device Type" "RESISTOR-G155-14701-01,4.7KOHMA"
			(at -0.008382 1.210564 180)
			(unlocked yes)
			(layer "B.Fab")
			(hide yes)
			(effects
				(font
					(size 0.7874 0.5842)
					(thickness 0.1524)
				)
				(justify mirror)
			)
		)
		(duplicate_pad_numbers_are_jumpers no)
		(fp_line
			(start 1.143 0.5588)
			(end -1.143 0.5588)
			(stroke
				(width 0.1)
				(type default)
			)
			(layer "B.SilkS")
		)
		(fp_line
			(start 1.143 -0.5588)
			(end 1.143 0.5588)
			(stroke
				(width 0.1)
				(type default)
			)
			(layer "B.SilkS")
		)
		(fp_line
			(start -1.143 0.5588)
			(end -1.143 -0.5588)
			(stroke
				(width 0.1)
				(type default)
			)
			(layer "B.SilkS")
		)
		(fp_line
			(start -1.143 -0.5588)
			(end 1.143 -0.5588)
			(stroke
				(width 0.1)
				(type default)
			)
			(layer "B.SilkS")
		)
		(fp_rect
			(start -1.143 0.5588)
			(end 1.143 -0.5588)
			(stroke
				(width 0)
				(type default)
			)
			(fill no)
			(layer "B.CrtYd")
		)
		(fp_line
			(start 0.508 0.3048)
			(end -0.508 0.3048)
			(stroke
				(width 0.1)
				(type default)
			)
			(layer "B.Fab")
		)
		(fp_line
			(start 0.508 -0.3048)
			(end 0.508 0.3048)
			(stroke
				(width 0.1)
				(type default)
			)
			(layer "B.Fab")
		)
		(fp_line
			(start -0.508 0.3048)
			(end -0.508 -0.3048)
			(stroke
				(width 0.1)
				(type default)
			)
			(layer "B.Fab")
		)
		(fp_line
			(start -0.508 -0.3048)
			(end 0.508 -0.3048)
			(stroke
				(width 0.1)
				(type default)
			)
			(layer "B.Fab")
		)
		(pad "1" smd rect
			(at 0.5334 0)
			(size 0.7112 0.6096)
			(layers "B.Cu" "B.Mask" "B.Paste")
			(net "SG")
		)
		(pad "2" smd rect
			(at -0.5334 0)
			(size 0.7112 0.6096)
			(layers "B.Cu" "B.Mask" "B.Paste")
			(net "UNNAMED_5_PCA9546APWTSSOP16_I33")
		)
		(zone
			(layer "B.Cu")
			(hatch none 0.5)
			(connect_pads
				(clearance 0)
			)
			(min_thickness 0.25)
			(keepout
				(tracks allowed)
				(vias not_allowed)
				(pads allowed)
				(copperpour not_allowed)
				(footprints allowed)
			)
			(placement
				(enabled no)
				(sheetname "")
			)
			(fill
				(thermal_gap 0.5)
				(thermal_bridge_width 0.5)
				(island_removal_mode 0)
			)
			(polygon
				(pts
					(xy 83.312 -82.8548) (xy 83.1596 -82.8548) (xy 83.1596 -82.2452) (xy 83.312 -82.2452)
				)
			)
		)
	)
)
